FILE_TYPE = CONNECTIVITY;
{Allegro Design Entry HDL 16.6-p007 (v16-6-112F) 10/10/2012}
"PAGE_NUMBER" = 35;
0"NC";
1"GND\g";
2"TP_CPU0_UPI2_RSVD_CC12";
3"TP_CPU0_UPI2_RSVD_CC10";
4"TP_CPU0_UPI2_RSVD_CE12";
5"TP_CPU0_UPI2_RSVD_CH11";
6"TP_CPU0_UPI2_RSVD_CF13";
7"TP_CPU0_UPI2_RSVD_CJ14";
8"TP_CPU0_UPI2_RSVD_CM13";
9"TP_CPU0_UPI2_RSVD_CU14";
10"TP_CPU0_UPI2_RSVD_CW14";
11"TP_CPU0_UPI2_RSVD_CA12";
12"TP_CPU0_UPI2_RSVD_CB11";
13"TP_CPU0_UPI2_RSVD_CD11";
14"TP_CPU0_UPI2_RSVD_CF11";
15"TP_CPU0_UPI2_RSVD_CG12";
16"TP_CPU0_UPI2_RSVD_CH13";
17"TP_CPU0_UPI2_RSVD_CK13";
18"TP_CPU0_UPI2_RSVD_CR14";
19"TP_CPU0_UPI2_RSVD_CV13";
20"TP_CPU0_UPI2_RSVD_CW16";
21"TP_CPU0_UPI2_RSVD_DB15";
22"TP_CPU0_UPI2_RSVD_DD15";
23"TP_CPU0_UPI2_RSVD_DE16";
24"TP_CPU0_UPI2_RSVD_DF17";
25"TP_CPU0_UPI2_RSVD_DH17";
26"TP_CPU0_UPI2_RSVD_DJ18";
27"TP_CPU0_UPI2_RSVD_DJ20";
28"TP_CPU0_UPI2_RSVD_DK19";
29"TP_CPU0_UPI2_RSVD_DN20";
30"TP_CPU0_UPI2_RSVD_DP21";
31"TP_CPU0_UPI2_RSVD_DA16";
32"TP_CPU0_UPI2_RSVD_DC16";
33"TP_CPU0_UPI2_RSVD_DF15";
34"TP_CPU0_UPI2_RSVD_DD17";
35"TP_CPU0_UPI2_RSVD_DG18";
36"TP_CPU0_UPI2_RSVD_DK17";
37"TP_CPU0_UPI2_RSVD_DH19";
38"TP_CPU0_UPI2_RSVD_DG20";
39"TP_CPU0_UPI2_RSVD_DL20";
40"TP_CPU0_UPI2_RSVD_DM21";
41"TP_CPU0_UPI2_RSVD_DT21";
%"GND"
"1","(-5975,1400)","0","mstr_symbols","I2";
;
HDL_POWER"GND"
BODY_TYPE"PLUMBING"
SIZE"1B"
CDS_LIB"mstr_symbols"
VOLTAGE"0.0V";
"A\NAC"1;
%"SKX_EXT_B"
"15","(-4225,2625)","0","chpset_lib","I3";
;
CDS_SEC"15"
ROOM"CPU0"
CDS_LOCATION"U5D1"
SEC"15"
SEC_TYPE"BGA1"
CDS_LIB"chpset_lib"
PACK_TYPE"BGA1"
MATERIAL"IC"
PART_NUMBER"TBD"
LOCATION"U5D1";
"UPI2_TX_DP<0>"
$PN"DP21"11;
"UPI2_TX_DP<1>"
$PN"DN20"12;
"UPI2_TX_DP<2>"
$PN"DK19"13;
"UPI2_TX_DP<3>"
$PN"DJ20"14;
"UPI2_TX_DP<4>"
$PN"DJ18"15;
"UPI2_TX_DP<5>"
$PN"DH17"16;
"UPI2_TX_DP<6>"
$PN"DF17"17;
"UPI2_TX_DP<7>"
$PN"DE16"18;
"UPI2_TX_DP<8>"
$PN"DD15"19;
"UPI2_TX_DP<9>"
$PN"DB15"20;
"UPI2_TX_DP<10>"
$PN"CW16"21;
"UPI2_TX_DP<11>"
$PN"CV13"22;
"UPI2_TX_DP<12>"
$PN"CR14"23;
"UPI2_TX_DP<13>"
$PN"CK13"24;
"UPI2_TX_DP<14>"
$PN"CH13"25;
"UPI2_TX_DP<15>"
$PN"CG12"26;
"UPI2_TX_DP<16>"
$PN"CF11"27;
"UPI2_TX_DP<17>"
$PN"CD11"28;
"UPI2_TX_DP<18>"
$PN"CB11"29;
"UPI2_TX_DP<19>"
$PN"CA12"30;
"UPI2_TX_DN<0>"
$PN"DT21"2;
"UPI2_TX_DN<1>"
$PN"DM21"3;
"UPI2_TX_DN<2>"
$PN"DL20"4;
"UPI2_TX_DN<3>"
$PN"DG20"5;
"UPI2_TX_DN<4>"
$PN"DH19"6;
"UPI2_TX_DN<5>"
$PN"DK17"7;
"UPI2_TX_DN<6>"
$PN"DG18"8;
"UPI2_TX_DN<7>"
$PN"DD17"9;
"UPI2_TX_DN<8>"
$PN"DF15"10;
"UPI2_TX_DN<9>"
$PN"DC16"31;
"UPI2_TX_DN<10>"
$PN"DA16"32;
"UPI2_TX_DN<11>"
$PN"CW14"33;
"UPI2_TX_DN<12>"
$PN"CU14"34;
"UPI2_TX_DN<13>"
$PN"CM13"35;
"UPI2_TX_DN<14>"
$PN"CJ14"36;
"UPI2_TX_DN<15>"
$PN"CF13"37;
"UPI2_TX_DN<16>"
$PN"CH11"38;
"UPI2_TX_DN<17>"
$PN"CE12"39;
"UPI2_TX_DN<18>"
$PN"CC10"40;
"UPI2_TX_DN<19>"
$PN"CC12"41;
"UPI2_RX_DP<0>"
$PN"DG22"1;
"UPI2_RX_DP<1>"
$PN"DD21"1;
"UPI2_RX_DP<2>"
$PN"DA22"1;
"UPI2_RX_DP<3>"
$PN"DC20"1;
"UPI2_RX_DP<4>"
$PN"DB19"1;
"UPI2_RX_DP<5>"
$PN"CY19"1;
"UPI2_RX_DP<6>"
$PN"CU20"1;
"UPI2_RX_DP<7>"
$PN"CW18"1;
"UPI2_RX_DP<8>"
$PN"CR20"1;
"UPI2_RX_DP<9>"
$PN"CN18"1;
"UPI2_RX_DP<10>"
$PN"CP19"1;
"UPI2_RX_DP<11>"
$PN"CM21"1;
"UPI2_RX_DP<12>"
$PN"CJ16"1;
"UPI2_RX_DP<13>"
$PN"CK17"1;
"UPI2_RX_DP<14>"
$PN"CG16"1;
"UPI2_RX_DP<15>"
$PN"CF15"1;
"UPI2_RX_DP<16>"
$PN"CC14"1;
"UPI2_RX_DP<17>"
$PN"CD17"1;
"UPI2_RX_DP<18>"
$PN"BY15"1;
"UPI2_RX_DP<19>"
$PN"CA16"1;
"UPI2_RX_DN<0>"
$PN"DF23"1;
"UPI2_RX_DN<1>"
$PN"DE22"1;
"UPI2_RX_DN<2>"
$PN"DC22"1;
"UPI2_RX_DN<3>"
$PN"DB21"1;
"UPI2_RX_DN<4>"
$PN"DD19"1;
"UPI2_RX_DN<5>"
$PN"DA20"1;
"UPI2_RX_DN<6>"
$PN"CW20"1;
"UPI2_RX_DN<7>"
$PN"CV19"1;
"UPI2_RX_DN<8>"
$PN"CT21"1;
"UPI2_RX_DN<9>"
$PN"CR18"1;
"UPI2_RX_DN<10>"
$PN"CN20"1;
"UPI2_RX_DN<11>"
$PN"CP21"1;
"UPI2_RX_DN<12>"
$PN"CL16"1;
"UPI2_RX_DN<13>"
$PN"CJ18"1;
"UPI2_RX_DN<14>"
$PN"CH17"1;
"UPI2_RX_DN<15>"
$PN"CE16"1;
"UPI2_RX_DN<16>"
$PN"CD15"1;
"UPI2_RX_DN<17>"
$PN"CF17"1;
"UPI2_RX_DN<18>"
$PN"CB15"1;
"UPI2_RX_DN<19>"
$PN"BY17"1;
END.
